(kicad_pcb
	(version 20260206)
	(generator "pcbnew")
	(generator_version "10.0")
	(general
		(thickness 1.6)
		(legacy_teardrops no)
	)
	(paper "A4")
	(title_block
		(title "timecard-production-celestica-r4006 — R4006-B0001-02_R01.brd")
		(comment 1 "Time Appliance Project (Time Card) / footprints 205-207 of 1113")
	)
	(layers
		(0 "F.Cu" signal "TOP")
		(4 "In1.Cu" signal "L02_GND1")
		(6 "In2.Cu" signal "L03_SIG1")
		(8 "In3.Cu" signal "L04_GND2")
		(10 "In4.Cu" signal "L05_VCC1")
		(12 "In5.Cu" signal "L06_VCC2")
		(14 "In6.Cu" signal "L07_GND3")
		(16 "In7.Cu" signal "L08_SIG2")
		(18 "In8.Cu" signal "L09_GND4")
		(2 "B.Cu" signal "BOTTOM")
		(9 "F.Adhes" user "F.Adhesive")
		(11 "B.Adhes" user "B.Adhesive")
		(13 "F.Paste" user "Package Geometry/Pastemask Top")
		(15 "B.Paste" user "Package Geometry/Pastemask Bottom")
		(5 "F.SilkS" user "Ref Des/Silkscreen Top")
		(7 "B.SilkS" user "Ref Des/Silkscreen Bottom")
		(1 "F.Mask" user "Board Geometry/Soldermask Top")
		(3 "B.Mask" user "Board Geometry/Soldermask Bottom")
		(17 "Dwgs.User" user "User.Drawings")
		(19 "Cmts.User" user "User.Comments")
		(21 "Eco1.User" user "User.Eco1")
		(23 "Eco2.User" user "User.Eco2")
		(25 "Edge.Cuts" user "Board Geometry/Outline")
		(27 "Margin" user)
		(31 "F.CrtYd" user "Package Geometry/Place Bound Top")
		(29 "B.CrtYd" user "Package Geometry/Place Bound Bottom")
		(35 "F.Fab" user "Ref Des/Assembly Top")
		(33 "B.Fab" user "Ref Des/Assembly Bottom")
	)
	(footprint ""
		(layer "F.Cu")
		(at 75.59548 -16.96212)
		(property "Reference" "C37"
			(at 0.35052 -2.81051 0)
			(unlocked yes)
			(layer "F.SilkS")
			(effects
				(font
					(size 0.7874 0.5842)
					(thickness 0.1524)
				)
			)
		)
		(property "Value" "VAL*"
			(at 0.0762 2.067306 0)
			(unlocked yes)
			(layer "F.Fab")
			(hide yes)
			(effects
				(font
					(size 0.7874 0.5842)
					(thickness 0.1524)
				)
			)
		)
		(property "Tolerance" "TOL*"
			(at 0.0762 3.032506 0)
			(unlocked yes)
			(layer "Cmts.User")
			(hide yes)
			(effects
				(font
					(size 0.7874 0.5842)
					(thickness 0.1524)
				)
			)
		)
		(property "User Part Number" "PARTNUM*"
			(at 0.1016 4.023106 0)
			(unlocked yes)
			(layer "Cmts.User")
			(hide yes)
			(effects
				(font
					(size 0.7874 0.5842)
					(thickness 0.1524)
				)
			)
		)
		(property "Device Type" "CAPACITOR-G105-0B104-CK,0.1UF,A"
			(at 0.0508 1.127506 0)
			(unlocked yes)
			(layer "F.Fab")
			(hide yes)
			(effects
				(font
					(size 0.7874 0.5842)
					(thickness 0.1524)
				)
			)
		)
		(duplicate_pad_numbers_are_jumpers no)
		(fp_line
			(start -1.143 -0.5588)
			(end -1.143 0.5588)
			(stroke
				(width 0.1)
				(type default)
			)
			(layer "F.SilkS")
		)
		(fp_line
			(start -1.143 0.5588)
			(end 1.143 0.5588)
			(stroke
				(width 0.1)
				(type default)
			)
			(layer "F.SilkS")
		)
		(fp_line
			(start 1.143 -0.5588)
			(end -1.143 -0.5588)
			(stroke
				(width 0.1)
				(type default)
			)
			(layer "F.SilkS")
		)
		(fp_line
			(start 1.143 0.5588)
			(end 1.143 -0.5588)
			(stroke
				(width 0.1)
				(type default)
			)
			(layer "F.SilkS")
		)
		(fp_rect
			(start -1.143 0.5588)
			(end 1.143 -0.5588)
			(stroke
				(width 0)
				(type default)
			)
			(fill no)
			(layer "F.CrtYd")
		)
		(fp_line
			(start -0.508 -0.3048)
			(end -0.508 0.3048)
			(stroke
				(width 0.1)
				(type default)
			)
			(layer "F.Fab")
		)
		(fp_line
			(start -0.508 0.3048)
			(end 0.508 0.3048)
			(stroke
				(width 0.1)
				(type default)
			)
			(layer "F.Fab")
		)
		(fp_line
			(start 0.508 -0.3048)
			(end -0.508 -0.3048)
			(stroke
				(width 0.1)
				(type default)
			)
			(layer "F.Fab")
		)
		(fp_line
			(start 0.508 0.3048)
			(end 0.508 -0.3048)
			(stroke
				(width 0.1)
				(type default)
			)
			(layer "F.Fab")
		)
		(pad "1" smd rect
			(at -0.5334 0)
			(size 0.7112 0.6096)
			(layers "F.Cu" "F.Mask" "F.Paste")
			(net "XP3R3V_FPGA")
		)
		(pad "2" smd rect
			(at 0.5334 0)
			(size 0.7112 0.6096)
			(layers "F.Cu" "F.Mask" "F.Paste")
			(net "SG")
		)
		(zone
			(layer "F.Cu")
			(hatch none 0.5)
			(connect_pads
				(clearance 0)
			)
			(min_thickness 0.25)
			(keepout
				(tracks allowed)
				(vias not_allowed)
				(pads allowed)
				(copperpour not_allowed)
				(footprints allowed)
			)
			(placement
				(enabled no)
				(sheetname "")
			)
			(fill
				(thermal_gap 0.5)
				(thermal_bridge_width 0.5)
				(island_removal_mode 0)
			)
			(polygon
				(pts
					(xy 75.51928 -16.65732) (xy 75.67168 -16.65732) (xy 75.67168 -17.26692) (xy 75.51928 -17.26692)
				)
			)
		)
	)
	(footprint ""
		(layer "F.Cu")
		(at 143.764 -88.138)
		(property "Reference" "TP43"
			(at -3.8862 -0.08763 0)
			(unlocked yes)
			(layer "F.SilkS")
			(effects
				(font
					(size 0.7874 0.5842)
					(thickness 0.1524)
				)
				(justify left)
			)
		)
		(property "Value" ""
			(at 0 0 0)
			(layer "F.Fab")
			(effects
				(font
					(size 1.27 1.27)
				)
			)
		)
		(property "Device Type" "TP_PIONT-TP010CT020B030_PTH-TPA"
			(at -1.341882 0.996696 0)
			(unlocked yes)
			(layer "F.Fab")
			(hide yes)
			(effects
				(font
					(size 0.7874 0.5842)
					(thickness 0.000001)
				)
				(justify left)
			)
		)
		(duplicate_pad_numbers_are_jumpers no)
		(fp_poly
			(pts
				(arc
					(start 0.889 0)
					(mid -0.889 0)
					(end 0.889 0)
				)
			)
			(stroke
				(width 0)
				(type default)
			)
			(fill no)
			(layer "B.CrtYd")
		)
		(fp_poly
			(pts
				(arc
					(start 0.889 0)
					(mid -0.889 0)
					(end 0.889 0)
				)
			)
			(stroke
				(width 0)
				(type default)
			)
			(fill no)
			(layer "F.CrtYd")
		)
		(pad "1" thru_hole circle
			(at 0 0)
			(size 0.508 0.508)
			(drill 0.254)
			(layers "*.Cu" "*.Mask")
			(remove_unused_layers no)
			(net "XP12R0V_A_EN")
			(clearance 0.1016)
			(padstack
				(mode front_inner_back)
				(layer "Inner"
					(shape circle)
					(size 0.508 0.508)
					(clearance 0.1016)
				)
				(layer "B.Cu"
					(shape circle)
					(size 0.762 0.762)
					(clearance -0.0254)
				)
			)
		)
	)
	(footprint ""
		(layer "F.Cu")
		(at 39.5224 -105.1814 90)
		(property "Reference" "R29"
			(at 1.58623 -1.5494 0)
			(unlocked yes)
			(layer "F.SilkS")
			(effects
				(font
					(size 0.7874 0.5842)
					(thickness 0.1524)
				)
			)
		)
		(property "Value" "VAL*"
			(at 0.02032 2.13233 90)
			(unlocked yes)
			(layer "F.Fab")
			(hide yes)
			(effects
				(font
					(size 0.7874 0.5842)
					(thickness 0.1524)
				)
			)
		)
		(property "Device Type" "RESISTOR-G155-11003-01,100KOHMA"
			(at 0.008382 1.210564 90)
			(unlocked yes)
			(layer "F.Fab")
			(hide yes)
			(effects
				(font
					(size 0.7874 0.5842)
					(thickness 0.1524)
				)
			)
		)
		(property "User Part Number" "PARTNUM*"
			(at 0.02032 4.024884 90)
			(unlocked yes)
			(layer "Cmts.User")
			(hide yes)
			(effects
				(font
					(size 0.7874 0.5842)
					(thickness 0.1524)
				)
			)
		)
		(property "Tolerance" "TOL*"
			(at 0.044704 3.05435 90)
			(unlocked yes)
			(layer "Cmts.User")
			(hide yes)
			(effects
				(font
					(size 0.7874 0.5842)
					(thickness 0.1524)
				)
			)
		)
		(duplicate_pad_numbers_are_jumpers no)
		(fp_line
			(start 1.143 -0.5588)
			(end -1.143 -0.5588)
			(stroke
				(width 0.1)
				(type default)
			)
			(layer "F.SilkS")
		)
		(fp_line
			(start -1.143 -0.5588)
			(end -1.143 0.5588)
			(stroke
				(width 0.1)
				(type default)
			)
			(layer "F.SilkS")
		)
		(fp_line
			(start 1.143 0.5588)
			(end 1.143 -0.5588)
			(stroke
				(width 0.1)
				(type default)
			)
			(layer "F.SilkS")
		)
		(fp_line
			(start -1.143 0.5588)
			(end 1.143 0.5588)
			(stroke
				(width 0.1)
				(type default)
			)
			(layer "F.SilkS")
		)
		(fp_rect
			(start 1.143 0.5588)
			(end -1.143 -0.5588)
			(stroke
				(width 0)
				(type default)
			)
			(fill no)
			(layer "F.CrtYd")
		)
		(fp_line
			(start 0.508 -0.3048)
			(end -0.508 -0.3048)
			(stroke
				(width 0.1)
				(type default)
			)
			(layer "F.Fab")
		)
		(fp_line
			(start -0.508 -0.3048)
			(end -0.508 0.3048)
			(stroke
				(width 0.1)
				(type default)
			)
			(layer "F.Fab")
		)
		(fp_line
			(start 0.508 0.3048)
			(end 0.508 -0.3048)
			(stroke
				(width 0.1)
				(type default)
			)
			(layer "F.Fab")
		)
		(fp_line
			(start -0.508 0.3048)
			(end 0.508 0.3048)
			(stroke
				(width 0.1)
				(type default)
			)
			(layer "F.Fab")
		)
		(pad "1" smd rect
			(at -0.5334 0 90)
			(size 0.7112 0.6096)
			(layers "F.Cu" "F.Mask" "F.Paste")
			(net "XP5R0V_RT")
		)
		(pad "2" smd rect
			(at 0.5334 0 90)
			(size 0.7112 0.6096)
			(layers "F.Cu" "F.Mask" "F.Paste")
			(net "XP5R0V_AGND")
		)
		(zone
			(layer "F.Cu")
			(hatch none 0.5)
			(connect_pads
				(clearance 0)
			)
			(min_thickness 0.25)
			(keepout
				(tracks allowed)
				(vias not_allowed)
				(pads allowed)
				(copperpour not_allowed)
				(footprints allowed)
			)
			(placement
				(enabled no)
				(sheetname "")
			)
			(fill
				(thermal_gap 0.5)
				(thermal_bridge_width 0.5)
				(island_removal_mode 0)
			)
			(polygon
				(pts
					(xy 39.8272 -105.2576) (xy 39.2176 -105.2576) (xy 39.2176 -105.1052) (xy 39.8272 -105.1052)
				)
			)
		)
	)
)
